FILE_TYPE = CONNECTIVITY;
{Allegro Design Entry HDL 17.2-2016 S066 (3851973) 4/6/2020}
"PAGE_NUMBER" = 517;
0"NC";
1"SG\g";
2"XP3R3V\g";
3"SG\g";
4"SG\g";
5"SG\g";
6"XP3R3V\g";
7"SG\g";
8"SG\g";
9"XP12R0V\g";
10"SG\g";
11"XP3R3V_EN";
12"R_XP3R3V_PG";
13"XP3R3V_SS";
14"XP3R3V_AGND"$PHYS_NET_NAME"XP5R0V_AGND";
15"XP3R3V_PG";
16"XP3R3V_FB_R_TO_AGND";
17"UN$517$CAPACITOR$I30$1";
18"XP3R3V_SW";
19"XP3R3V_AGND";
20"VIN_XP3R3";
21"XP3R3V_RT";
22"XP3R3V_BT";
23"UN$517$CAPACITOR$I17$1";
24"XP3R3V_COMP";
25"UN$517$CAPACITOR$I27$1";
26"UN$517$CAPACITOR$I29$2";
%"GND_SG"
"1","(-12000,3400)","0","cls","I1";
;
HDL_POWER"SG"
BODY_TYPE"PLUMBING"
CDS_LIB"cls"
CDS_LMAN_SYM_OUTLINE"0,0,100,-50";
"SGND"4;
%"RESISTOR"
"2","(-11050,5300)","0","passive","I10";
;
$LOCATION"R35"
CDS_LOCATION"R35"
$SEC"1"
CDS_SEC"1"
PACKAGE"0402"
VALUE"100KOHM"
TOLERANCE"1%"
CLS_PN"G155-11003-01"
CDS_LMAN_SYM_OUTLINE"-50,50,50,-100"
CDS_LIB"passive";
"1"
$PN"1"21;
"2"
$PN"2"14;
%"RESISTOR"
"2","(-13300,5750)","0","passive","I11";
;
$LOCATION"R52"
CDS_LOCATION"R52"
$SEC"1"
CDS_SEC"1"
VALUE"5.1KOHM"
PACKAGE"0402"
TOLERANCE"1%"
CLS_PN"G155-05101-01"
CDS_LMAN_SYM_OUTLINE"-50,50,50,-100"
CDS_LIB"passive";
"1"
$PN"1"11;
"2"
$PN"2"5;
%"CAPACITOR"
"2","(-12350,5800)","0","passive","I12";
;
$LOCATION"C46"
CDS_LOCATION"C46"
$SEC"1"
CDS_SEC"1"
VALUE"0.1UF"
PACKAGE"0402"
VOLTAGE"10V"
CDS_LIB"passive"
CDS_LMAN_SYM_OUTLINE"-50,0,50,-50"
TOLERANCE"10%"
CLS_PN"G105-0B104-CK";
"2"
$PN"2"5;
"1"
$PN"1"11;
%"RESISTOR"
"2","(-12550,6850)","0","passive","I13";
;
$LOCATION"R53"
CDS_LOCATION"R53"
$SEC"1"
CDS_SEC"1"
PACKAGE"0402"
VALUE"30KOHM"
CLS_PN"G152-10344-01"
TOLERANCE"0.1%"
CDS_LIB"passive"
CDS_LMAN_SYM_OUTLINE"-50,50,50,-100";
"1"
$PN"1"20;
"2"
$PN"2"11;
%"CAPACITOR"
"2","(-12000,7150)","0","passive","I14";
;
$LOCATION"C48"
CDS_LOCATION"C48"
$SEC"1"
CDS_SEC"1"
VALUE"10UF"
VOLTAGE"25V"
PACKAGE"0805"
TOLERANCE"20%"
CDS_LIB"passive"
CDS_LMAN_SYM_OUTLINE"-50,0,50,-50"
CLS_PN"G107-0F106-EM";
"2"
$PN"2"10;
"1"
$PN"1"20;
%"CAPACITOR"
"2","(-11550,7150)","0","passive","I15";
;
$LOCATION"C50"
CDS_LOCATION"C50"
$SEC"1"
CDS_SEC"1"
VALUE"10UF"
PACKAGE"0805"
VOLTAGE"25V"
CDS_LIB"passive"
CDS_LMAN_SYM_OUTLINE"-50,0,50,-50"
CLS_PN"G107-0F106-EM"
TOLERANCE"20%";
"2"
$PN"2"10;
"1"
$PN"1"20;
%"CAPACITOR"
"2","(-11100,7150)","0","passive","I16";
;
$LOCATION"C52"
CDS_LOCATION"C52"
$SEC"1"
CDS_SEC"1"
VALUE"0.1UF"
PACKAGE"0402"
VOLTAGE"25V"
CDS_LIB"passive"
CDS_LMAN_SYM_OUTLINE"-50,0,50,-50"
CLS_PN"G105-0B104-EK"
TOLERANCE"10%";
"2"
$PN"2"10;
"1"
$PN"1"20;
%"CAPACITOR"
"2","(-10400,4900)","0","passive","I17";
;
$LOCATION"C54"
CDS_LOCATION"C54"
$SEC"1"
CDS_SEC"1"
VOLTAGE"50V"
VALUE"2200PF"
PACKAGE"0402"
CLS_PN"G105-0B222-FK"
CDS_LIB"passive"
CDS_LMAN_SYM_OUTLINE"-50,0,50,-50"
TOLERANCE"10%";
"2"
$PN"2"14;
"1"
$PN"1"23;
%"RESISTOR"
"2","(-10400,5200)","0","passive","I18";
;
$LOCATION"R36"
CDS_LOCATION"R36"
$SEC"1"
CDS_SEC"1"
VALUE"10KOHM"
PACKAGE"0402"
CLS_PN"G155-11002-01"
CDS_LIB"passive"
CDS_LMAN_SYM_OUTLINE"-50,50,50,-100"
TOLERANCE"1%";
"1"
$PN"1"24;
"2"
$PN"2"23;
%"CAPACITOR"
"2","(-9800,5050)","0","passive","I19";
;
$LOCATION"C55"
CDS_LOCATION"C55"
$SEC"1"
CDS_SEC"1"
PACKAGE"0201"
VOLTAGE"25V"
VALUE"18PF"
TOLERANCE"5%"
CDS_LIB"passive"
CDS_LMAN_SYM_OUTLINE"-50,0,50,-50"
CLS_PN"G104-0A180-FJ";
"2"
$PN"2"14;
"1"
$PN"1"24;
%"CAPACITOR"
"1","(-11950,3700)","1","passive","I2";
;
$LOCATION"C77"
CDS_LOCATION"C77"
$SEC"1"
CDS_SEC"1"
VOLTAGE"25V"
VALUE"0.01UF"
PACKAGE"0402"
CLS_PN"G104-0B103-EK"
CDS_LMAN_SYM_OUTLINE"0,50,50,-50"
CDS_LIB"passive"
TOLERANCE"10%";
"2"
$PN"2"12;
"1"
$PN"1"4;
%"GND_SG"
"1","(-10600,6600)","0","cls","I20";
;
HDL_POWER"SG"
BODY_TYPE"PLUMBING"
CDS_LIB"cls"
CDS_LMAN_SYM_OUTLINE"0,0,100,-50";
"SGND"10;
%"CAPACITOR"
"2","(-10550,7150)","0","passive","I21";
;
$LOCATION"C53"
CDS_LOCATION"C53"
$SEC"1"
CDS_SEC"1"
VALUE"0.1UF"
PACKAGE"0402"
VOLTAGE"25V"
CLS_PN"G105-0B104-EK"
CDS_LIB"passive"
CDS_LMAN_SYM_OUTLINE"-50,0,50,-50"
TOLERANCE"10%";
"2"
$PN"2"10;
"1"
$PN"1"20;
%"VCC"
"1","(-13800,7900)","0","cls","I22";
;
HDL_POWER"XP12R0V"
VOLTAGE"12V"
BODY_TYPE"PLUMBING"
CDS_LMAN_SYM_OUTLINE"-250,250,250,-250"
CDS_LIB"cls";
"$PIN0"9;
%"GND_SG"
"1","(-7800,3950)","0","cls","I23";
;
HDL_POWER"SG"
BODY_TYPE"PLUMBING"
CDS_LMAN_SYM_OUTLINE"0,0,100,-50"
CDS_LIB"cls";
"SGND"8;
%"SOLDER_PREFORM"
"1","(-7150,4350)","0","mech","I24";
;
$LOCATION"SP2"
CDS_LOCATION"SP2"
$SEC"1"
CDS_SEC"1"
CLS_PN"G380-10015-01"
CDS_LMAN_SYM_OUTLINE"0,0,250,-200"
CDS_LIB"mech";
"2"
$PN"2"19;
"1"
$PN"1"8;
%"RESISTOR"
"1","(-6850,6500)","0","passive","I25";
;
$LOCATION"R37"
CDS_LOCATION"R37"
$SEC"1"
CDS_SEC"1"
VALUE"0OHM"
PACKAGE"0402"
TOLERANCE"-"
CLS_PN"G155-100R0-J0"
CDS_LIB"passive"
CDS_LMAN_SYM_OUTLINE"-50,50,100,-50";
"1"
$PN"1"22;
"2"
$PN"2"25;
%"RESISTOR"
"2","(-5150,4600)","0","passive","I26";
;
$LOCATION"R38"
CDS_LOCATION"R38"
$SEC"1"
CDS_SEC"1"
PACKAGE"0402"
VALUE"4.42KOHM"
TOLERANCE"1%"
CLS_PN"G155-04421-01"
CDS_LIB"passive"
CDS_LMAN_SYM_OUTLINE"-50,50,50,-100";
"1"
$PN"1"16;
"2"
$PN"2"19;
%"CAPACITOR"
"1","(-5950,6500)","0","passive","I27";
;
$LOCATION"C56"
CDS_LOCATION"C56"
$SEC"1"
CDS_SEC"1"
VOLTAGE"25V"
VALUE"0.1UF"
PACKAGE"0402"
TOLERANCE"10%"
CDS_LMAN_SYM_OUTLINE"0,50,50,-50"
CDS_LIB"passive"
CLS_PN"G105-0B104-EK";
"2"
$PN"2"18;
"1"
$PN"1"25;
%"INDUCTOR_2"
"1","(-4600,6300)","0","passive","I28";
;
$LOCATION"L2"
CDS_LOCATION"L2"
$SEC"1"
CDS_SEC"1"
VALUE"4.7UH"
CLS_PN"G190-10424-01"
CDS_LMAN_SYM_OUTLINE"-100,50,150,-50"
CDS_LIB"passive"
TOLERANCE"20%";
"1"
$PN"1"18;
"2"
$PN"2"6;
%"CAPACITOR"
"1","(-4650,6650)","0","passive","I29";
;
$LOCATION"C57"
CDS_LOCATION"C57"
$SEC"1"
CDS_SEC"1"
VOLTAGE"50V"
NO_ASSY"TRUE"
PACKAGE"0402"
VALUE"1000PF"
TOLERANCE"5%"
CDS_LIB"passive"
CDS_LMAN_SYM_OUTLINE"0,50,50,-50"
CLS_PN"G105-0A102-FJ";
"2"
$PN"2"26;
"1"
$PN"1"18;
%"RESISTOR"
"2","(-13000,4450)","0","passive","I3";
;
$LOCATION"R51"
CDS_LOCATION"R51"
$SEC"1"
CDS_SEC"1"
PACKAGE"0402"
VALUE"10KOHM"
TOLERANCE"1%"
CLS_PN"G155-11002-01"
CDS_LIB"passive"
CDS_LMAN_SYM_OUTLINE"-50,50,50,-100";
"1"
$PN"1"2;
"2"
$PN"2"12;
%"CAPACITOR"
"2","(-3750,5300)","0","passive","I30";
;
$LOCATION"C16"
CDS_LOCATION"C16"
$SEC"1"
CDS_SEC"1"
VALUE"100PF"
PACKAGE"0201"
VOLTAGE"50V"
TOLERANCE"10%"
CDS_LMAN_SYM_OUTLINE"-50,0,50,-50"
CDS_LIB"passive"
CLS_PN"G104-0B101-FK";
"2"
$PN"2"16;
"1"
$PN"1"17;
%"RESISTOR"
"2","(-3100,5350)","0","passive","I31";
;
$LOCATION"R40"
CDS_LOCATION"R40"
$SEC"1"
CDS_SEC"1"
VALUE"20KOHM"
PACKAGE"0402"
TOLERANCE"1%"
CLS_PN"G155-12002-01"
CDS_LMAN_SYM_OUTLINE"-50,50,50,-100"
CDS_LIB"passive";
"1"
$PN"1"17;
"2"
$PN"2"16;
%"RESISTOR"
"1","(-3650,6650)","0","passive","I32";
;
$LOCATION"R39"
CDS_LOCATION"R39"
$SEC"1"
CDS_SEC"1"
NO_ASSY"TRUE"
VALUE"2.2OHM"
PACKAGE"0805"
TOLERANCE"1%"
CDS_LMAN_SYM_OUTLINE"-50,50,100,-50"
CDS_LIB"passive"
CLS_PN"G157-12R20-01";
"1"
$PN"1"26;
"2"
$PN"2"3;
%"RESISTOR"
"2","(-3100,5900)","0","passive","I33";
;
$LOCATION"R17"
CDS_LOCATION"R17"
$SEC"1"
CDS_SEC"1"
VALUE"20OHM"
PACKAGE"0402"
TOLERANCE"1%"
CDS_LMAN_SYM_OUTLINE"-50,50,50,-100"
CDS_LIB"passive"
CLS_PN"G155-120R0-01";
"1"
$PN"1"6;
"2"
$PN"2"17;
%"GND_SG"
"1","(-3200,6500)","0","cls","I34";
;
HDL_POWER"SG"
BODY_TYPE"PLUMBING"
CDS_LIB"cls"
CDS_LMAN_SYM_OUTLINE"0,0,100,-50";
"SGND"3;
%"GND_SG"
"1","(-1100,5250)","0","cls","I35";
;
HDL_POWER"SG"
BODY_TYPE"PLUMBING"
CDS_LIB"cls"
CDS_LMAN_SYM_OUTLINE"0,0,100,-50";
"SGND"7;
%"CAPACITOR"
"2","(-2500,5950)","0","passive","I36";
;
$LOCATION"C18"
CDS_LOCATION"C18"
$SEC"1"
CDS_SEC"1"
VOLTAGE"10V"
PACKAGE"0402"
VALUE"0.1UF"
TOLERANCE"10%"
CDS_LMAN_SYM_OUTLINE"-50,0,50,-50"
CDS_LIB"passive"
CLS_PN"G105-0B104-CK";
"2"
$PN"2"7;
"1"
$PN"1"6;
%"CAPACITOR"
"2","(-2000,5950)","0","passive","I37";
;
$LOCATION"C20"
CDS_LOCATION"C20"
$SEC"1"
CDS_SEC"1"
VOLTAGE"10V"
PACKAGE"0805"
VALUE"22UF"
CLS_PN"G107-0F226-CM"
CDS_LIB"passive"
CDS_LMAN_SYM_OUTLINE"-50,0,50,-50"
TOLERANCE"20%";
"2"
$PN"2"7;
"1"
$PN"1"6;
%"CAPACITOR"
"2","(-1500,5950)","0","passive","I38";
;
$LOCATION"C21"
CDS_LOCATION"C21"
$SEC"1"
CDS_SEC"1"
VOLTAGE"10V"
VALUE"22UF"
PACKAGE"0805"
CLS_PN"G107-0F226-CM"
CDS_LIB"passive"
CDS_LMAN_SYM_OUTLINE"-50,0,50,-50"
TOLERANCE"20%";
"2"
$PN"2"7;
"1"
$PN"1"6;
%"VCC"
"1","(-1100,6700)","0","cls","I39";
;
HDL_POWER"XP3R3V"
VOLTAGE"3.3"
BODY_TYPE"PLUMBING"
CDS_LIB"cls"
CDS_LMAN_SYM_OUTLINE"-250,250,250,-250";
"$PIN0"6;
%"CAPACITOR"
"2","(-1050,5950)","0","passive","I40";
;
$LOCATION"C22"
CDS_LOCATION"C22"
$SEC"1"
CDS_SEC"1"
VOLTAGE"10V"
VALUE"22UF"
PACKAGE"0805"
CLS_PN"G107-0F226-CM"
CDS_LMAN_SYM_OUTLINE"-50,0,50,-50"
CDS_LIB"passive"
TOLERANCE"20%";
"2"
$PN"2"7;
"1"
$PN"1"6;
%"RESISTOR"
"1","(-4550,4550)","1","passive","I41";
;
$LOCATION"R54"
CDS_LOCATION"R54"
$SEC"1"
CDS_SEC"1"
VALUE"0OHM"
NO_ASSY"TRUE"
PACKAGE"0603"
TOLERANCE"-"
CLS_PN"G156-100R0-J0"
CDS_LMAN_SYM_OUTLINE"-50,50,100,-50"
CDS_LIB"passive";
"1"
$PN"1"19;
"2"
$PN"2"16;
%"TPS54824RNVR_VQFN18"
"1","(-9200,6600)","0","stdlogic","I42";
;
$LOCATION"U6"
CDS_LOCATION"U6"
$SEC"1"
CDS_SEC"1"
VALUE"TPS54424RNVT"
CLS_PN"G220-10657-01"
CDS_LMAN_SYM_OUTLINE"0,0,1000,-1750"
CDS_LIB"stdlogic";
"PGOOD"
$PN"18"12;
"EN"
$PN"17"11;
"SS/TRK"
$PN"16"13;
"COMP"
$PN"15"24;
"FB"
$PN"14"16;
"RT/CLK"
$PN"13"21;
"AGND"
$PN"12"14;
"VIN_2"
$PN"11"20;
"PGND_6"
$PN"10"8;
"PGND_5"
$PN"9"8;
"PGND_4"
$PN"8"8;
"SW_2"
$PN"7"18;
"SW_1"
$PN"6"18;
"PGND_3"
$PN"5"8;
"PGND_2"
$PN"4"8;
"PGND_1"
$PN"3"8;
"VIN_1"
$PN"2"20;
"BOOT"
$PN"1"22;
%"RESISTOR"
"1","(-11350,4100)","0","passive","I47";
;
$LOCATION"R263"
CDS_LOCATION"R263"
$SEC"1"
CDS_SEC"1"
VALUE"0OHM"
PACKAGE"0402"
TOLERANCE"-"
CDS_LIB"passive"
CDS_LMAN_SYM_OUTLINE"-50,50,100,-50"
CLS_PN"G155-100R0-J0";
"1"
$PN"1"12;
"2"
$PN"2"15;
%"VCC"
"1","(-13050,4750)","0","cls","I49";
;
HDL_POWER"XP3R3V"
VOLTAGE"3.3"
BODY_TYPE"PLUMBING"
CDS_LIB"cls"
CDS_LMAN_SYM_OUTLINE"-250,250,250,-250";
"$PIN0"2;
%"GND_SG"
"1","(-13800,6800)","0","cls","I5";
;
HDL_POWER"SG"
BODY_TYPE"PLUMBING"
CDS_LIB"cls"
CDS_LMAN_SYM_OUTLINE"0,0,100,-50";
"SGND"1;
%"CAPACITOR"
"2","(-12850,5800)","0","passive","I51";
;
$LOCATION"C286"
CDS_LOCATION"C286"
$SEC"1"
CDS_SEC"1"
VOLTAGE"25V"
VALUE"0.22UF"
PACKAGE"0402"
CLS_PN"G105-0B224-DK"
TOLERANCE"10%"
CDS_LIB"passive"
CDS_LMAN_SYM_OUTLINE"-50,0,50,-50";
"2"
$PN"2"5;
"1"
$PN"1"11;
%"CAPACITOR"
"2","(-13750,7200)","0","passive","I6";
;
$LOCATION"C76"
CDS_LOCATION"C76"
$SEC"1"
CDS_SEC"1"
VALUE"0.1UF"
PACKAGE"0402"
VOLTAGE"25V"
TOLERANCE"10%"
CLS_PN"G105-0B104-EK"
CDS_LIB"passive"
CDS_LMAN_SYM_OUTLINE"-50,0,50,-50";
"2"
$PN"2"1;
"1"
$PN"1"9;
%"FERRITEBEAD"
"1","(-13250,7500)","0","passive","I7";
;
$LOCATION"L8"
CDS_LOCATION"L8"
$SEC"1"
CDS_SEC"1"
PACKAGE"0603"
VALUE"26OHM"
TOLERANCE"25%"
CLS_PN"G191-10101-01"
CDS_LIB"passive"
CDS_LMAN_SYM_OUTLINE"0,0,200,-100";
"2"
$PN"2"20;
"1"
$PN"1"9;
%"GND_SG"
"1","(-12400,5250)","0","cls","I8";
;
HDL_POWER"SG"
BODY_TYPE"PLUMBING"
CDS_LIB"cls"
CDS_LMAN_SYM_OUTLINE"0,0,100,-50";
"SGND"5;
%"CAPACITOR"
"2","(-11600,5300)","0","passive","I9";
;
$LOCATION"C49"
CDS_LOCATION"C49"
$SEC"1"
CDS_SEC"1"
PACKAGE"0402"
VALUE"0.022UF"
TOLERANCE"10%"
CDS_LIB"passive"
CDS_LMAN_SYM_OUTLINE"-50,0,50,-50"
CLS_PN"G105-0B223-EK";
"2"
$PN"2"14;
"1"
$PN"1"13;
END.
